# SCM (Grand Teton) — schematic netlist excerpt (pin names and nets, part order shuffled) for the footprints in the layout excerpt that follows; sources: Cadence DE-HDL packaged netlist, KiCad conversion of 12092022_DA0F0TMDCD0_F0T_Management_Board_D_brd_V3_OCP.brd

R589  Q_RES  33.2 1% CHIP  pkg 0402LF  page 12 : A = SMB_BMC_MM3_R_SCL ; B = SMB_BMC_MM3_SCL
C113  Q_CAP  22UF 6.3V 20% X6S  pkg C0603  page 16 : A = P1V0_AUX ; B = GND

(kicad_pcb
	(version 20260206)
	(generator "pcbnew")
	(generator_version "10.0")
	(general
		(thickness 1.6)
		(legacy_teardrops no)
	)
	(paper "A4")
	(title_block
		(title "12092022_DA0F0TMDCD0_F0T_Management_Board_D_brd_V3_OCP.brd")
		(comment 1 "Grand Teton / footprints 1035-1036 of 1440")
	)
	(layers
		(0 "F.Cu" signal "TOP")
		(4 "In1.Cu" signal "GND")
		(6 "In2.Cu" signal "IN1")
		(8 "In3.Cu" signal "GND1")
		(10 "In4.Cu" signal "IN2")
		(12 "In5.Cu" signal "VCC")
		(14 "In6.Cu" signal "VCC1")
		(16 "In7.Cu" signal "IN3")
		(18 "In8.Cu" signal "GND2")
		(20 "In9.Cu" signal "IN4")
		(22 "In10.Cu" signal "GND3")
		(2 "B.Cu" signal "BOTTOM")
		(9 "F.Adhes" user "F.Adhesive")
		(11 "B.Adhes" user "B.Adhesive")
		(13 "F.Paste" user "Package Geometry/Pastemask Top")
		(15 "B.Paste" user "Package Geometry/Pastemask Bottom")
		(5 "F.SilkS" user "Ref Des/Silkscreen Top")
		(7 "B.SilkS" user "Ref Des/Silkscreen Bottom")
		(1 "F.Mask" user "Board Geometry/Soldermask Top")
		(3 "B.Mask" user "Board Geometry/Soldermask Bottom")
		(17 "Dwgs.User" user "User.Drawings")
		(19 "Cmts.User" user "User.Comments")
		(21 "Eco1.User" user "User.Eco1")
		(23 "Eco2.User" user "User.Eco2")
		(25 "Edge.Cuts" user "Board Geometry/Outline")
		(27 "Margin" user)
		(31 "F.CrtYd" user "Package Geometry/Place Bound Top")
		(29 "B.CrtYd" user "Package Geometry/Place Bound Bottom")
		(35 "F.Fab" user "Ref Des/Assembly Top")
		(33 "B.Fab" user "Ref Des/Assembly Bottom")
	)
	(footprint ""
		(layer "B.Cu")
		(at 69.85 -57.023)
		(property "Reference" "C113"
			(at 0 0 0)
			(layer "B.SilkS")
			(hide yes)
			(effects
				(font
					(size 1.27 1.27)
				)
				(justify mirror)
			)
		)
		(property "Value" ""
			(at 0 0 0)
			(layer "B.Fab")
			(effects
				(font
					(size 1.27 1.27)
				)
				(justify mirror)
			)
		)
		(duplicate_pad_numbers_are_jumpers no)
		(fp_line
			(start -1.2954 -0.5842)
			(end -1.2954 0.5842)
			(stroke
				(width 0.1524)
				(type default)
			)
			(layer "B.SilkS")
		)
		(fp_line
			(start -1.2954 0.5842)
			(end 1.2954 0.5842)
			(stroke
				(width 0.1524)
				(type default)
			)
			(layer "B.SilkS")
		)
		(fp_line
			(start 0 -0.5842)
			(end 0 0.5842)
			(stroke
				(width 0.1524)
				(type default)
			)
			(layer "B.SilkS")
		)
		(fp_line
			(start 1.2954 -0.5842)
			(end -1.2954 -0.5842)
			(stroke
				(width 0.1524)
				(type default)
			)
			(layer "B.SilkS")
		)
		(fp_line
			(start 1.2954 0.5842)
			(end 1.2954 -0.5842)
			(stroke
				(width 0.1524)
				(type default)
			)
			(layer "B.SilkS")
		)
		(fp_line
			(start -1.1938 -0.4064)
			(end -1.1938 0.4064)
			(stroke
				(width 0.1)
				(type default)
			)
			(layer "B.Fab")
		)
		(fp_line
			(start -1.1938 0.4064)
			(end -0.8636 0.4064)
			(stroke
				(width 0.1)
				(type default)
			)
			(layer "B.Fab")
		)
		(fp_line
			(start -0.8636 -0.4572)
			(end -0.8636 -0.4064)
			(stroke
				(width 0.1)
				(type default)
			)
			(layer "B.Fab")
		)
		(fp_line
			(start -0.8636 -0.4064)
			(end -1.1938 -0.4064)
			(stroke
				(width 0.1)
				(type default)
			)
			(layer "B.Fab")
		)
		(fp_line
			(start -0.8636 0.4064)
			(end -0.8636 0.4572)
			(stroke
				(width 0.1)
				(type default)
			)
			(layer "B.Fab")
		)
		(fp_line
			(start -0.8636 0.4572)
			(end 0.8636 0.4572)
			(stroke
				(width 0.1)
				(type default)
			)
			(layer "B.Fab")
		)
		(fp_line
			(start 0.8636 -0.4572)
			(end -0.8636 -0.4572)
			(stroke
				(width 0.1)
				(type default)
			)
			(layer "B.Fab")
		)
		(fp_line
			(start 0.8636 -0.4064)
			(end 0.8636 -0.4572)
			(stroke
				(width 0.1)
				(type default)
			)
			(layer "B.Fab")
		)
		(fp_line
			(start 0.8636 0.4064)
			(end 1.1938 0.4064)
			(stroke
				(width 0.1)
				(type default)
			)
			(layer "B.Fab")
		)
		(fp_line
			(start 0.8636 0.4572)
			(end 0.8636 0.4064)
			(stroke
				(width 0.1)
				(type default)
			)
			(layer "B.Fab")
		)
		(fp_line
			(start 1.1938 -0.4064)
			(end 0.8636 -0.4064)
			(stroke
				(width 0.1)
				(type default)
			)
			(layer "B.Fab")
		)
		(fp_line
			(start 1.1938 0.4064)
			(end 1.1938 -0.4064)
			(stroke
				(width 0.1)
				(type default)
			)
			(layer "B.Fab")
		)
		(pad "1" smd rect
			(at 0.7366 0 270)
			(size 0.7112 0.8128)
			(layers "B.Cu" "B.Mask" "B.Paste")
			(net "P1V0_AUX")
		)
		(pad "2" smd rect
			(at -0.7366 0 270)
			(size 0.7112 0.8128)
			(layers "B.Cu" "B.Mask" "B.Paste")
			(net "GND")
		)
	)
	(footprint ""
		(layer "B.Cu")
		(at 47.498 -34.671 90)
		(property "Reference" "R589"
			(at 0 0 90)
			(layer "B.SilkS")
			(hide yes)
			(effects
				(font
					(size 1.27 1.27)
				)
				(justify mirror)
			)
		)
		(property "Value" ""
			(at 0 0 90)
			(layer "B.Fab")
			(effects
				(font
					(size 1.27 1.27)
				)
				(justify mirror)
			)
		)
		(duplicate_pad_numbers_are_jumpers no)
		(fp_line
			(start 0.7874 -0.4064)
			(end -0.7874 -0.4064)
			(stroke
				(width 0.1524)
				(type default)
			)
			(layer "B.SilkS")
		)
		(fp_line
			(start -0.7874 -0.4064)
			(end -0.7874 0.4064)
			(stroke
				(width 0.1524)
				(type default)
			)
			(layer "B.SilkS")
		)
		(fp_line
			(start 0.7874 0.4064)
			(end 0.7874 -0.4064)
			(stroke
				(width 0.1524)
				(type default)
			)
			(layer "B.SilkS")
		)
		(fp_line
			(start -0.7874 0.4064)
			(end 0.7874 0.4064)
			(stroke
				(width 0.1524)
				(type default)
			)
			(layer "B.SilkS")
		)
		(fp_line
			(start 0.67945 -0.305054)
			(end 0.12065 -0.305054)
			(stroke
				(width 0.1)
				(type default)
			)
			(layer "B.Fab")
		)
		(fp_line
			(start 0.12065 -0.305054)
			(end 0.12065 -0.2794)
			(stroke
				(width 0.1)
				(type default)
			)
			(layer "B.Fab")
		)
		(fp_line
			(start -0.12065 -0.3048)
			(end -0.67945 -0.3048)
			(stroke
				(width 0.1)
				(type default)
			)
			(layer "B.Fab")
		)
		(fp_line
			(start -0.67945 -0.3048)
			(end -0.67945 0.3048)
			(stroke
				(width 0.1)
				(type default)
			)
			(layer "B.Fab")
		)
		(fp_line
			(start 0.12065 -0.2794)
			(end -0.12065 -0.2794)
			(stroke
				(width 0.1)
				(type default)
			)
			(layer "B.Fab")
		)
		(fp_line
			(start -0.12065 -0.2794)
			(end -0.12065 -0.3048)
			(stroke
				(width 0.1)
				(type default)
			)
			(layer "B.Fab")
		)
		(fp_line
			(start 0.12065 0.2794)
			(end 0.12065 0.3048)
			(stroke
				(width 0.1)
				(type default)
			)
			(layer "B.Fab")
		)
		(fp_line
			(start -0.120396 0.2794)
			(end 0.12065 0.2794)
			(stroke
				(width 0.1)
				(type default)
			)
			(layer "B.Fab")
		)
		(fp_line
			(start 0.67945 0.3048)
			(end 0.67945 -0.305054)
			(stroke
				(width 0.1)
				(type default)
			)
			(layer "B.Fab")
		)
		(fp_line
			(start 0.12065 0.3048)
			(end 0.67945 0.3048)
			(stroke
				(width 0.1)
				(type default)
			)
			(layer "B.Fab")
		)
		(fp_line
			(start -0.120396 0.3048)
			(end -0.120396 0.2794)
			(stroke
				(width 0.1)
				(type default)
			)
			(layer "B.Fab")
		)
		(fp_line
			(start -0.67945 0.3048)
			(end -0.120396 0.3048)
			(stroke
				(width 0.1)
				(type default)
			)
			(layer "B.Fab")
		)
		(pad "1" smd circle
			(at 0.40005 0 270)
			(size 0 0)
			(layers "B.Cu" "B.Mask" "B.Paste")
			(net "SMB_BMC_MM3_R_SCL")
		)
		(pad "2" smd circle
			(at -0.40005 0 270)
			(size 0 0)
			(layers "B.Cu" "B.Mask" "B.Paste")
			(net "SMB_BMC_MM3_SCL")
		)
	)
)
